# T6G (Grand Teton) — schematic netlist excerpt (pin names and nets, part order shuffled) for the footprints in the layout excerpt that follows; sources: Cadence DE-HDL packaged netlist, KiCad conversion of 04192023_DAF0TMB3IC0_F0TG_MB_C_brd_V02_OCP.brd

R1791  Q_RES  9.09K 1% CHIP  pkg 0402LF  page 257 : A = P5V_ADC ; B = GND

U30  SN74LVC1G07DBVR  IC  pkg SMLF  page 136
  NC  = NC
  A  = OCP_V3_1_P3V3_R2_PWRGD
  GND  = GND
  Y  = OCP_V3_1_P3V3_PLD_PWRGD
  VCC  = P3V3_AUX

(kicad_pcb
	(version 20260206)
	(generator "pcbnew")
	(generator_version "10.0")
	(general
		(thickness 1.6)
		(legacy_teardrops no)
	)
	(paper "A4")
	(title_block
		(title "04192023_DAF0TMB3IC0_F0TG_MB_C_brd_V02_OCP.brd")
		(comment 1 "Grand Teton / footprints 4374-4375 of 8354")
	)
	(layers
		(0 "F.Cu" signal "TOP")
		(4 "In1.Cu" signal "GND")
		(6 "In2.Cu" signal "IN1")
		(8 "In3.Cu" signal "GND1")
		(10 "In4.Cu" signal "IN2")
		(12 "In5.Cu" signal "GND2")
		(14 "In6.Cu" signal "IN3")
		(16 "In7.Cu" signal "GND3")
		(18 "In8.Cu" signal "VCC")
		(20 "In9.Cu" signal "VCC1")
		(22 "In10.Cu" signal "GND4")
		(24 "In11.Cu" signal "IN4")
		(26 "In12.Cu" signal "GND5")
		(28 "In13.Cu" signal "IN5")
		(30 "In14.Cu" signal "GND6")
		(32 "In15.Cu" signal "IN6")
		(34 "In16.Cu" signal "GND7")
		(2 "B.Cu" signal "BOTTOM")
		(9 "F.Adhes" user "F.Adhesive")
		(11 "B.Adhes" user "B.Adhesive")
		(13 "F.Paste" user "Package Geometry/Pastemask Top")
		(15 "B.Paste" user "Package Geometry/Pastemask Bottom")
		(5 "F.SilkS" user "Ref Des/Silkscreen Top")
		(7 "B.SilkS" user "Ref Des/Silkscreen Bottom")
		(1 "F.Mask" user "Board Geometry/Soldermask Top")
		(3 "B.Mask" user "Board Geometry/Soldermask Bottom")
		(17 "Dwgs.User" user "User.Drawings")
		(19 "Cmts.User" user "User.Comments")
		(21 "Eco1.User" user "User.Eco1")
		(23 "Eco2.User" user "User.Eco2")
		(25 "Edge.Cuts" user "Board Geometry/Outline")
		(27 "Margin" user)
		(31 "F.CrtYd" user "Package Geometry/Place Bound Top")
		(29 "B.CrtYd" user "Package Geometry/Place Bound Bottom")
		(35 "F.Fab" user "Ref Des/Assembly Top")
		(33 "B.Fab" user "Ref Des/Assembly Bottom")
	)
	(footprint ""
		(layer "F.Cu")
		(at 327.179178 -43.573954)
		(property "Reference" "R1791"
			(at 0 0 0)
			(layer "F.SilkS")
			(hide yes)
			(effects
				(font
					(size 1.27 1.27)
				)
			)
		)
		(property "Value" ""
			(at 0 0 0)
			(layer "F.Fab")
			(effects
				(font
					(size 1.27 1.27)
				)
			)
		)
		(duplicate_pad_numbers_are_jumpers no)
		(fp_line
			(start -0.7874 -0.4064)
			(end 0.7874 -0.4064)
			(stroke
				(width 0.1524)
				(type default)
			)
			(layer "F.SilkS")
		)
		(fp_line
			(start -0.7874 0.4064)
			(end -0.7874 -0.4064)
			(stroke
				(width 0.1524)
				(type default)
			)
			(layer "F.SilkS")
		)
		(fp_line
			(start 0.7874 -0.4064)
			(end 0.7874 0.4064)
			(stroke
				(width 0.1524)
				(type default)
			)
			(layer "F.SilkS")
		)
		(fp_line
			(start 0.7874 0.4064)
			(end -0.7874 0.4064)
			(stroke
				(width 0.1524)
				(type default)
			)
			(layer "F.SilkS")
		)
		(fp_line
			(start -0.67945 -0.305054)
			(end -0.12065 -0.305054)
			(stroke
				(width 0.1)
				(type default)
			)
			(layer "F.Fab")
		)
		(fp_line
			(start -0.67945 0.3048)
			(end -0.67945 -0.305054)
			(stroke
				(width 0.1)
				(type default)
			)
			(layer "F.Fab")
		)
		(fp_line
			(start -0.12065 -0.305054)
			(end -0.12065 -0.2794)
			(stroke
				(width 0.1)
				(type default)
			)
			(layer "F.Fab")
		)
		(fp_line
			(start -0.12065 -0.2794)
			(end 0.12065 -0.2794)
			(stroke
				(width 0.1)
				(type default)
			)
			(layer "F.Fab")
		)
		(fp_line
			(start -0.12065 0.2794)
			(end -0.12065 0.3048)
			(stroke
				(width 0.1)
				(type default)
			)
			(layer "F.Fab")
		)
		(fp_line
			(start -0.12065 0.3048)
			(end -0.67945 0.3048)
			(stroke
				(width 0.1)
				(type default)
			)
			(layer "F.Fab")
		)
		(fp_line
			(start 0.120396 0.2794)
			(end -0.12065 0.2794)
			(stroke
				(width 0.1)
				(type default)
			)
			(layer "F.Fab")
		)
		(fp_line
			(start 0.120396 0.3048)
			(end 0.120396 0.2794)
			(stroke
				(width 0.1)
				(type default)
			)
			(layer "F.Fab")
		)
		(fp_line
			(start 0.12065 -0.3048)
			(end 0.67945 -0.3048)
			(stroke
				(width 0.1)
				(type default)
			)
			(layer "F.Fab")
		)
		(fp_line
			(start 0.12065 -0.2794)
			(end 0.12065 -0.3048)
			(stroke
				(width 0.1)
				(type default)
			)
			(layer "F.Fab")
		)
		(fp_line
			(start 0.67945 -0.3048)
			(end 0.67945 0.3048)
			(stroke
				(width 0.1)
				(type default)
			)
			(layer "F.Fab")
		)
		(fp_line
			(start 0.67945 0.3048)
			(end 0.120396 0.3048)
			(stroke
				(width 0.1)
				(type default)
			)
			(layer "F.Fab")
		)
		(pad "1" smd circle
			(at -0.40005 0)
			(size 0 0)
			(layers "F.Cu" "F.Mask" "F.Paste")
			(net "P5V_ADC")
		)
		(pad "2" smd circle
			(at 0.40005 0)
			(size 0 0)
			(layers "F.Cu" "F.Mask" "F.Paste")
			(net "GND")
		)
	)
	(footprint ""
		(layer "F.Cu")
		(at 167.386 -95.377 90)
		(property "Reference" "U30"
			(at -3.544316 -2.646172 90)
			(unlocked yes)
			(layer "F.SilkS")
			(effects
				(font
					(size 0.7874 0.5842)
					(thickness 0.1524)
				)
				(justify left)
			)
		)
		(property "Value" ""
			(at 0 0 90)
			(layer "F.Fab")
			(effects
				(font
					(size 1.27 1.27)
				)
			)
		)
		(duplicate_pad_numbers_are_jumpers no)
		(fp_line
			(start 2.0574 -1.651)
			(end 2.0574 1.651)
			(stroke
				(width 0.1524)
				(type default)
			)
			(layer "F.SilkS")
		)
		(fp_line
			(start 0.381 -1.651)
			(end 2.0574 -1.651)
			(stroke
				(width 0.1524)
				(type default)
			)
			(layer "F.SilkS")
		)
		(fp_line
			(start -0.381 -1.651)
			(end 0 -1.016)
			(stroke
				(width 0.1524)
				(type default)
			)
			(layer "F.SilkS")
		)
		(fp_line
			(start -2.0574 -1.651)
			(end -0.381 -1.651)
			(stroke
				(width 0.1524)
				(type default)
			)
			(layer "F.SilkS")
		)
		(fp_line
			(start 0 -1.016)
			(end 0.381 -1.651)
			(stroke
				(width 0.1524)
				(type default)
			)
			(layer "F.SilkS")
		)
		(fp_line
			(start 2.0574 1.651)
			(end -2.0574 1.651)
			(stroke
				(width 0.1524)
				(type default)
			)
			(layer "F.SilkS")
		)
		(fp_line
			(start -2.0574 1.651)
			(end -2.0574 -1.651)
			(stroke
				(width 0.1524)
				(type default)
			)
			(layer "F.SilkS")
		)
		(fp_poly
			(pts
				(xy -2.71272 -0.719328) (xy -2.71272 -1.344168) (xy -2.159 -1.016)
			)
			(stroke
				(width 0)
				(type default)
			)
			(fill yes)
			(layer "F.SilkS")
		)
		(fp_line
			(start 0.899922 -1.549908)
			(end 0.899922 -1.199896)
			(stroke
				(width 0.1)
				(type default)
			)
			(layer "F.Fab")
		)
		(fp_line
			(start -0.899922 -1.549908)
			(end 0.899922 -1.549908)
			(stroke
				(width 0.1)
				(type default)
			)
			(layer "F.Fab")
		)
		(fp_line
			(start 1.599946 -1.199896)
			(end 1.599946 1.199896)
			(stroke
				(width 0.1)
				(type default)
			)
			(layer "F.Fab")
		)
		(fp_line
			(start 0.899922 -1.199896)
			(end 1.599946 -1.199896)
			(stroke
				(width 0.1)
				(type default)
			)
			(layer "F.Fab")
		)
		(fp_line
			(start -0.899922 -1.199896)
			(end -0.899922 -1.549908)
			(stroke
				(width 0.1)
				(type default)
			)
			(layer "F.Fab")
		)
		(fp_line
			(start -1.599946 -1.199896)
			(end -0.899922 -1.199896)
			(stroke
				(width 0.1)
				(type default)
			)
			(layer "F.Fab")
		)
		(fp_line
			(start 1.599946 1.199896)
			(end 0.899922 1.199896)
			(stroke
				(width 0.1)
				(type default)
			)
			(layer "F.Fab")
		)
		(fp_line
			(start 0.899922 1.199896)
			(end 0.899922 1.549908)
			(stroke
				(width 0.1)
				(type default)
			)
			(layer "F.Fab")
		)
		(fp_line
			(start -0.899922 1.199896)
			(end -1.599946 1.199896)
			(stroke
				(width 0.1)
				(type default)
			)
			(layer "F.Fab")
		)
		(fp_line
			(start -1.599946 1.199896)
			(end -1.599946 -1.199896)
			(stroke
				(width 0.1)
				(type default)
			)
			(layer "F.Fab")
		)
		(fp_line
			(start 0.899922 1.549908)
			(end -0.899922 1.549908)
			(stroke
				(width 0.1)
				(type default)
			)
			(layer "F.Fab")
		)
		(fp_line
			(start -0.899922 1.549908)
			(end -0.899922 1.199896)
			(stroke
				(width 0.1)
				(type default)
			)
			(layer "F.Fab")
		)
		(fp_poly
			(pts
				(xy -2.71272 -0.719328) (xy -2.71272 -1.344168) (xy -2.159 -1.016)
			)
			(stroke
				(width 0)
				(type default)
			)
			(fill yes)
			(layer "F.Fab")
		)
		(pad "1" smd rect
			(at -1.225042 -0.94996)
			(size 0.5588 1.3462)
			(layers "F.Cu" "F.Mask" "F.Paste")
			(net "Net_10854")
		)
		(pad "2" smd rect
			(at -1.225042 0)
			(size 0.5588 1.3462)
			(layers "F.Cu" "F.Mask" "F.Paste")
			(net "OCP_V3_1_P3V3_R2_PWRGD")
		)
		(pad "3" smd rect
			(at -1.225042 0.94996)
			(size 0.5588 1.3462)
			(layers "F.Cu" "F.Mask" "F.Paste")
			(net "GND")
		)
		(pad "4" smd rect
			(at 1.225042 0.94996)
			(size 0.5588 1.3462)
			(layers "F.Cu" "F.Mask" "F.Paste")
			(net "OCP_V3_1_P3V3_PLD_PWRGD")
		)
		(pad "5" smd rect
			(at 1.225042 -0.94996)
			(size 0.5588 1.3462)
			(layers "F.Cu" "F.Mask" "F.Paste")
			(net "P3V3_AUX")
		)
	)
)
